# S9S_MB_2U (Grand Teton) — schematic netlist excerpt (pin names and nets, part order shuffled) for the footprints in the layout excerpt that follows; sources: Cadence DE-HDL packaged netlist, KiCad conversion of 03242023_DA0F0TMBIJ0_F0T_Motherboard_J_brd_V01_OCP.brd

D73  Q_LED  IC  pkg SMLF  page 253 : A = LED_PWRGD_PVCCD_HV_CPU0 ; C = LED_PWRGD_PVCCD_HV_CPU0_D
R2907  Q_RES  5.11K 1% CHIP  pkg 0402LF  page 250 : A = P3V3_AUX ; B = P3V3_AUX_ADC

(kicad_pcb
	(version 20260206)
	(generator "pcbnew")
	(generator_version "10.0")
	(general
		(thickness 1.6)
		(legacy_teardrops no)
	)
	(paper "A4")
	(title_block
		(title "03242023_DA0F0TMBIJ0_F0T_Motherboard_J_brd_V01_OCP.brd")
		(comment 1 "Grand Teton / footprints 1940-1941 of 6105")
	)
	(layers
		(0 "F.Cu" signal "TOP")
		(4 "In1.Cu" signal "GND")
		(6 "In2.Cu" signal "IN1")
		(8 "In3.Cu" signal "GND1")
		(10 "In4.Cu" signal "IN2")
		(12 "In5.Cu" signal "GND2")
		(14 "In6.Cu" signal "IN3")
		(16 "In7.Cu" signal "GND3")
		(18 "In8.Cu" signal "VCC")
		(20 "In9.Cu" signal "VCC1")
		(22 "In10.Cu" signal "GND4")
		(24 "In11.Cu" signal "IN4")
		(26 "In12.Cu" signal "GND5")
		(28 "In13.Cu" signal "IN5")
		(30 "In14.Cu" signal "GND6")
		(32 "In15.Cu" signal "IN6")
		(34 "In16.Cu" signal "GND7")
		(2 "B.Cu" signal "BOTTOM")
		(9 "F.Adhes" user "F.Adhesive")
		(11 "B.Adhes" user "B.Adhesive")
		(13 "F.Paste" user "Package Geometry/Pastemask Top")
		(15 "B.Paste" user "Package Geometry/Pastemask Bottom")
		(5 "F.SilkS" user "Ref Des/Silkscreen Top")
		(7 "B.SilkS" user "Ref Des/Silkscreen Bottom")
		(1 "F.Mask" user "Board Geometry/Soldermask Top")
		(3 "B.Mask" user "Board Geometry/Soldermask Bottom")
		(17 "Dwgs.User" user "User.Drawings")
		(19 "Cmts.User" user "User.Comments")
		(21 "Eco1.User" user "User.Eco1")
		(23 "Eco2.User" user "User.Eco2")
		(25 "Edge.Cuts" user "Board Geometry/Outline")
		(27 "Margin" user)
		(31 "F.CrtYd" user "Package Geometry/Place Bound Top")
		(29 "B.CrtYd" user "Package Geometry/Place Bound Bottom")
		(35 "F.Fab" user "Ref Des/Assembly Top")
		(33 "B.Fab" user "Ref Des/Assembly Bottom")
	)
	(footprint ""
		(layer "F.Cu")
		(at 83.996276 -79.078836)
		(property "Reference" "D73"
			(at -42.90441 34.331402 90)
			(unlocked yes)
			(layer "F.SilkS")
			(effects
				(font
					(size 0.635 0.4064)
					(thickness 0.1524)
				)
				(justify left)
			)
		)
		(property "Value" ""
			(at 0 0 0)
			(layer "F.Fab")
			(effects
				(font
					(size 1.27 1.27)
				)
			)
		)
		(duplicate_pad_numbers_are_jumpers no)
		(fp_line
			(start -0.90678 0.4826)
			(end -0.90678 -0.4699)
			(stroke
				(width 0.1524)
				(type default)
			)
			(layer "F.SilkS")
		)
		(fp_line
			(start -0.89408 -0.4826)
			(end 0.90678 -0.4826)
			(stroke
				(width 0.1524)
				(type default)
			)
			(layer "F.SilkS")
		)
		(fp_line
			(start -0.79248 -0.4826)
			(end 1.03378 -0.4826)
			(stroke
				(width 0.1524)
				(type default)
			)
			(layer "F.SilkS")
		)
		(fp_line
			(start -0.64008 -0.4826)
			(end 1.16078 -0.4826)
			(stroke
				(width 0.1524)
				(type default)
			)
			(layer "F.SilkS")
		)
		(fp_line
			(start 0.90678 -0.4826)
			(end 0.90678 0.4826)
			(stroke
				(width 0.1524)
				(type default)
			)
			(layer "F.SilkS")
		)
		(fp_line
			(start 0.90678 0.4826)
			(end -0.90678 0.4826)
			(stroke
				(width 0.1524)
				(type default)
			)
			(layer "F.SilkS")
		)
		(fp_line
			(start 1.03378 -0.4826)
			(end 1.03378 0.4826)
			(stroke
				(width 0.1524)
				(type default)
			)
			(layer "F.SilkS")
		)
		(fp_line
			(start 1.03378 0.4826)
			(end -0.79248 0.4826)
			(stroke
				(width 0.1524)
				(type default)
			)
			(layer "F.SilkS")
		)
		(fp_line
			(start 1.16078 -0.4826)
			(end 1.16078 0.4826)
			(stroke
				(width 0.1524)
				(type default)
			)
			(layer "F.SilkS")
		)
		(fp_line
			(start 1.16078 0.4826)
			(end -0.64008 0.4826)
			(stroke
				(width 0.1524)
				(type default)
			)
			(layer "F.SilkS")
		)
		(fp_line
			(start -0.499872 -0.249936)
			(end 0.499872 -0.249936)
			(stroke
				(width 0.1)
				(type default)
			)
			(layer "F.Fab")
		)
		(fp_line
			(start -0.499872 0.249936)
			(end -0.499872 -0.249936)
			(stroke
				(width 0.1)
				(type default)
			)
			(layer "F.Fab")
		)
		(fp_line
			(start 0.499872 -0.249936)
			(end 0.499872 0.249936)
			(stroke
				(width 0.1)
				(type default)
			)
			(layer "F.Fab")
		)
		(fp_line
			(start 0.499872 0.249936)
			(end -0.499872 0.249936)
			(stroke
				(width 0.1)
				(type default)
			)
			(layer "F.Fab")
		)
		(pad "A" smd rect
			(at -0.47498 0)
			(size 0.6096 0.7112)
			(layers "F.Cu" "F.Mask" "F.Paste")
			(net "LED_PWRGD_PVCCD_HV_CPU0")
		)
		(pad "C" smd rect
			(at 0.47498 0)
			(size 0.6096 0.7112)
			(layers "F.Cu" "F.Mask" "F.Paste")
			(net "LED_PWRGD_PVCCD_HV_CPU0_D")
		)
	)
	(footprint ""
		(layer "F.Cu")
		(at 46.582584 -107.031282 180)
		(property "Reference" "R2907"
			(at 0 0 180)
			(layer "F.SilkS")
			(hide yes)
			(effects
				(font
					(size 1.27 1.27)
				)
			)
		)
		(property "Value" ""
			(at 0 0 180)
			(layer "F.Fab")
			(effects
				(font
					(size 1.27 1.27)
				)
			)
		)
		(duplicate_pad_numbers_are_jumpers no)
		(fp_line
			(start 0.7874 0.4064)
			(end -0.7874 0.4064)
			(stroke
				(width 0.1524)
				(type default)
			)
			(layer "F.SilkS")
		)
		(fp_line
			(start 0.7874 -0.4064)
			(end 0.7874 0.4064)
			(stroke
				(width 0.1524)
				(type default)
			)
			(layer "F.SilkS")
		)
		(fp_line
			(start -0.7874 0.4064)
			(end -0.7874 -0.4064)
			(stroke
				(width 0.1524)
				(type default)
			)
			(layer "F.SilkS")
		)
		(fp_line
			(start -0.7874 -0.4064)
			(end 0.7874 -0.4064)
			(stroke
				(width 0.1524)
				(type default)
			)
			(layer "F.SilkS")
		)
		(fp_line
			(start 0.67945 0.3048)
			(end 0.120396 0.3048)
			(stroke
				(width 0.1)
				(type default)
			)
			(layer "F.Fab")
		)
		(fp_line
			(start 0.67945 -0.3048)
			(end 0.67945 0.3048)
			(stroke
				(width 0.1)
				(type default)
			)
			(layer "F.Fab")
		)
		(fp_line
			(start 0.12065 -0.2794)
			(end 0.12065 -0.3048)
			(stroke
				(width 0.1)
				(type default)
			)
			(layer "F.Fab")
		)
		(fp_line
			(start 0.12065 -0.3048)
			(end 0.67945 -0.3048)
			(stroke
				(width 0.1)
				(type default)
			)
			(layer "F.Fab")
		)
		(fp_line
			(start 0.120396 0.3048)
			(end 0.120396 0.2794)
			(stroke
				(width 0.1)
				(type default)
			)
			(layer "F.Fab")
		)
		(fp_line
			(start 0.120396 0.2794)
			(end -0.12065 0.2794)
			(stroke
				(width 0.1)
				(type default)
			)
			(layer "F.Fab")
		)
		(fp_line
			(start -0.12065 0.3048)
			(end -0.67945 0.3048)
			(stroke
				(width 0.1)
				(type default)
			)
			(layer "F.Fab")
		)
		(fp_line
			(start -0.12065 0.2794)
			(end -0.12065 0.3048)
			(stroke
				(width 0.1)
				(type default)
			)
			(layer "F.Fab")
		)
		(fp_line
			(start -0.12065 -0.2794)
			(end 0.12065 -0.2794)
			(stroke
				(width 0.1)
				(type default)
			)
			(layer "F.Fab")
		)
		(fp_line
			(start -0.12065 -0.305054)
			(end -0.12065 -0.2794)
			(stroke
				(width 0.1)
				(type default)
			)
			(layer "F.Fab")
		)
		(fp_line
			(start -0.67945 0.3048)
			(end -0.67945 -0.305054)
			(stroke
				(width 0.1)
				(type default)
			)
			(layer "F.Fab")
		)
		(fp_line
			(start -0.67945 -0.305054)
			(end -0.12065 -0.305054)
			(stroke
				(width 0.1)
				(type default)
			)
			(layer "F.Fab")
		)
		(pad "1" smd circle
			(at -0.40005 0 180)
			(size 0 0)
			(layers "F.Cu" "F.Mask" "F.Paste")
			(net "P3V3_AUX")
		)
		(pad "2" smd circle
			(at 0.40005 0 180)
			(size 0 0)
			(layers "F.Cu" "F.Mask" "F.Paste")
			(net "P3V3_AUX_ADC")
		)
	)
)
